(kicad_pcb
	(version 20241229)
	(generator "pcbnew")
	(generator_version "9.0")
	(general
		(thickness 1.62)
		(legacy_teardrops no)
	)
	(paper "A4")
	(title_block
		(title "OCuLink to 10GbE adapter")
		(date "2026-02-23")
		(rev "1.1.0")
		(company "Antmicro Ltd")
		(comment 1 "www.antmicro.com")
		(comment 9 "footprint 265 of 510 (U9), pads 245-323 of 503")
	)
	(layers
		(0 "F.Cu" signal)
		(4 "In1.Cu" signal)
		(6 "In2.Cu" signal)
		(8 "In3.Cu" signal)
		(10 "In4.Cu" signal)
		(12 "In5.Cu" signal)
		(14 "In6.Cu" signal)
		(2 "B.Cu" signal)
		(9 "F.Adhes" user "F.Adhesive")
		(11 "B.Adhes" user "B.Adhesive")
		(13 "F.Paste" user)
		(15 "B.Paste" user)
		(5 "F.SilkS" user "F.Silkscreen")
		(7 "B.SilkS" user "B.Silkscreen")
		(1 "F.Mask" user)
		(3 "B.Mask" user)
		(17 "Dwgs.User" user "User.Drawings")
		(19 "Cmts.User" user "User.Comments")
		(21 "Eco1.User" user "User.Eco1")
		(23 "Eco2.User" user "User.Eco2")
		(25 "Edge.Cuts" user)
		(27 "Margin" user)
		(31 "F.CrtYd" user "F.Courtyard")
		(29 "B.CrtYd" user "B.Courtyard")
		(35 "F.Fab" user)
		(33 "B.Fab" user)
	)
	(footprint "antmicro-footprints:FCBGA-503_22x22mm_Layout21x24_P1mm"
		(locked yes)
		(layer "F.Cu")
		(at 84.975 100 180)
		(property "Reference" "U9"
			(at -11.275 11.4 0)
			(layer "F.SilkS")
			(effects
				(font
					(size 0.7 0.7)
					(thickness 0.15)
				)
				(justify right bottom)
			)
		)
		(property "Value" "EZX710AT2_S_LMR5"
			(at -11.4 12.5 0)
			(layer "F.Fab")
			(hide yes)
			(effects
				(font
					(size 0.7 0.7)
					(thickness 0.15)
				)
				(justify right top)
			)
		)
		(property "Datasheet" "https://www.google.com/url?sa=t&source=web&rct=j&opi=89978449&url=https://cdrdv2-public.intel.com/596333/596333_X710-TM4_Datasheet_v_2_4.pdf&ved=2ahUKEwiSuv20_sCOAxXVCRAIHdxGO_UQFnoECBEQAQ&usg=AOvVaw1CjGyrGWE8ZvOdw4VBsY6U"
			(at -16.625 -13.91 0)
			(layer "F.Fab")
			(hide yes)
			(effects
				(font
					(size 0.7 0.7)
					(thickness 0.15)
				)
				(justify right top)
			)
		)
		(property "Description" "Ethernet ICs Intel Ethernet Controller 10 Gigabit X7"
			(at -12.015 -0.89 0)
			(layer "F.Fab")
			(hide yes)
			(effects
				(font
					(size 0.7 0.7)
					(thickness 0.15)
				)
				(justify right top)
			)
		)
		(property "MPN" "EZX710AT2 S LMR5"
			(at 0 0 180)
			(unlocked yes)
			(layer "F.Fab")
			(hide yes)
			(effects
				(font
					(size 1 1)
					(thickness 0.15)
				)
			)
		)
		(property "Manufacturer" "Intel"
			(at 0 0 180)
			(unlocked yes)
			(layer "F.Fab")
			(hide yes)
			(effects
				(font
					(size 1 1)
					(thickness 0.15)
				)
			)
		)
		(property "Author" "Antmicro"
			(at 0 0 180)
			(unlocked yes)
			(layer "F.Fab")
			(hide yes)
			(effects
				(font
					(size 1 1)
					(thickness 0.15)
				)
			)
		)
		(property "License" "Apache-2.0"
			(at 0 0 180)
			(unlocked yes)
			(layer "F.Fab")
			(hide yes)
			(effects
				(font
					(size 1 1)
					(thickness 0.15)
				)
			)
		)
		(sheetname "/X710-AT2 power/")
		(sheetfile "x710-at2-power.kicad_sch")
		(attr smd)
		(pad "H30" smd circle
			(at 4.25 -3.895 180)
			(size 0.5 0.5)
			(layers "F.Cu" "F.Mask" "F.Paste")
			(net 28 "GND")
			(pinfunction "VSSA")
			(pintype "passive")
		)
		(pad "H32" smd circle
			(at 5.25 -3.895 180)
			(size 0.5 0.5)
			(layers "F.Cu" "F.Mask" "F.Paste")
			(net 28 "GND")
			(pinfunction "VSSA")
			(pintype "passive")
		)
		(pad "H34" smd circle
			(at 6.25 -3.895 180)
			(size 0.5 0.5)
			(layers "F.Cu" "F.Mask" "F.Paste")
			(net 28 "GND")
			(pinfunction "VSSA")
			(pintype "passive")
		)
		(pad "H36" smd circle
			(at 7.25 -3.895 180)
			(size 0.5 0.5)
			(layers "F.Cu" "F.Mask" "F.Paste")
			(net 28 "GND")
			(pinfunction "VSSA")
			(pintype "passive")
		)
		(pad "H38" smd circle
			(at 8.25 -3.895 180)
			(size 0.5 0.5)
			(layers "F.Cu" "F.Mask" "F.Paste")
			(net 28 "GND")
			(pinfunction "VSSA")
			(pintype "passive")
		)
		(pad "H40" smd circle
			(at 9.25 -3.895 180)
			(size 0.5 0.5)
			(layers "F.Cu" "F.Mask" "F.Paste")
			(net 28 "GND")
			(pinfunction "RSVDH40_VSS")
			(pintype "passive")
		)
		(pad "H42" smd circle
			(at 10.25 -3.895 180)
			(size 0.5 0.5)
			(layers "F.Cu" "F.Mask" "F.Paste")
			(net 346 "unconnected-(U9F-XTAL_PTP_XTAL_N-PadH42)")
			(pinfunction "XTAL_PTP_XTAL_N")
			(pintype "passive+no_connect")
		)
		(pad "J1" smd circle
			(at -10.25 -3.03 180)
			(size 0.5 0.5)
			(layers "F.Cu" "F.Mask" "F.Paste")
			(net 161 "Net-(U9D-NCSI_RXD_0)")
			(pinfunction "NCSI_RXD_0")
			(pintype "output")
		)
		(pad "J3" smd circle
			(at -9.25 -3.03 180)
			(size 0.5 0.5)
			(layers "F.Cu" "F.Mask" "F.Paste")
			(net 162 "Net-(U9D-NCSI_RXD_1)")
			(pinfunction "NCSI_RXD_1")
			(pintype "output")
		)
		(pad "J5" smd circle
			(at -8.25 -3.03 180)
			(size 0.5 0.5)
			(layers "F.Cu" "F.Mask" "F.Paste")
			(net 160 "Net-(U9D-NCSI_CRS_DV)")
			(pinfunction "NCSI_CRS_DV")
			(pintype "output")
		)
		(pad "J7" smd circle
			(at -7.25 -3.03 180)
			(size 0.5 0.5)
			(layers "F.Cu" "F.Mask" "F.Paste")
			(net 174 "unconnected-(U9C-SDP2_1-PadJ7)")
			(pinfunction "SDP2_1")
			(pintype "passive+no_connect")
		)
		(pad "J9" smd circle
			(at -6.25 -3.03 180)
			(size 0.5 0.5)
			(layers "F.Cu" "F.Mask" "F.Paste")
			(net 85 "/X710-AT2 10GbE/OSC_SEL")
			(pinfunction "OSC_SEL")
			(pintype "tri_state")
		)
		(pad "J11" smd circle
			(at -5.25 -3.03 180)
			(size 0.5 0.5)
			(layers "F.Cu" "F.Mask" "F.Paste")
			(net 115 "/X710-AT2 Misc/RSVD_J11_VSS")
			(pinfunction "RSVD_J11_VSS")
			(pintype "passive")
		)
		(pad "J13" smd circle
			(at -4.25 -3.03 180)
			(size 0.5 0.5)
			(layers "F.Cu" "F.Mask" "F.Paste")
			(net 28 "GND")
			(pinfunction "RSVDJ13_VSS")
			(pintype "passive")
		)
		(pad "J15" smd circle
			(at -3.25 -3.03 180)
			(size 0.5 0.5)
			(layers "F.Cu" "F.Mask" "F.Paste")
			(net 249 "unconnected-(U9F-RSVDJ15_NC-PadJ15)")
			(pinfunction "RSVDJ15_NC")
			(pintype "passive+no_connect")
		)
		(pad "J17" smd circle
			(at -2.25 -3.03 180)
			(size 0.5 0.5)
			(layers "F.Cu" "F.Mask" "F.Paste")
			(net 28 "GND")
			(pinfunction "RSVDJ17_VSS")
			(pintype "passive")
		)
		(pad "J19" smd circle
			(at -1.25 -3.03 180)
			(size 0.5 0.5)
			(layers "F.Cu" "F.Mask" "F.Paste")
			(net 28 "GND")
			(pinfunction "RSVDJ19_VSS")
			(pintype "passive")
		)
		(pad "J21" smd circle
			(at -0.25 -3.03 180)
			(size 0.5 0.5)
			(layers "F.Cu" "F.Mask" "F.Paste")
			(net 28 "GND")
			(pinfunction "RSVDJ21_VSS")
			(pintype "passive")
		)
		(pad "J23" smd circle
			(at 0.75 -3.03 180)
			(size 0.5 0.5)
			(layers "F.Cu" "F.Mask" "F.Paste")
			(net 239 "unconnected-(U9E-RSVDJ23_NC-PadJ23)")
			(pinfunction "RSVDJ23_NC")
			(pintype "passive+no_connect")
		)
		(pad "J25" smd circle
			(at 1.75 -3.03 180)
			(size 0.5 0.5)
			(layers "F.Cu" "F.Mask" "F.Paste")
			(net 236 "unconnected-(U9E-RSVDJ25_NC-PadJ25)")
			(pinfunction "RSVDJ25_NC")
			(pintype "passive+no_connect")
		)
		(pad "J27" smd circle
			(at 2.75 -3.03 180)
			(size 0.5 0.5)
			(layers "F.Cu" "F.Mask" "F.Paste")
			(net 12 "XFI_VDD")
			(pinfunction "XFI_VDD")
			(pintype "power_in")
		)
		(pad "J29" smd circle
			(at 3.75 -3.03 180)
			(size 0.5 0.5)
			(layers "F.Cu" "F.Mask" "F.Paste")
			(net 12 "XFI_VDD")
			(pinfunction "XFI_VDD")
			(pintype "passive")
		)
		(pad "J31" smd circle
			(at 4.75 -3.03 180)
			(size 0.5 0.5)
			(layers "F.Cu" "F.Mask" "F.Paste")
			(net 12 "XFI_VDD")
			(pinfunction "XFI_VDD")
			(pintype "passive")
		)
		(pad "J33" smd circle
			(at 5.75 -3.03 180)
			(size 0.5 0.5)
			(layers "F.Cu" "F.Mask" "F.Paste")
			(net 24 "XFI_PVDD")
			(pinfunction "XFI_PVDD")
			(pintype "power_in")
		)
		(pad "J35" smd circle
			(at 6.75 -3.03 180)
			(size 0.5 0.5)
			(layers "F.Cu" "F.Mask" "F.Paste")
			(net 12 "XFI_VDD")
			(pinfunction "XFI_VDD")
			(pintype "passive")
		)
		(pad "J37" smd circle
			(at 7.75 -3.03 180)
			(size 0.5 0.5)
			(layers "F.Cu" "F.Mask" "F.Paste")
			(net 83 "/X710-AT2 10GbE/RESCAL_RES_P")
			(pinfunction "RESCAL_RES_P")
			(pintype "passive")
		)
		(pad "J39" smd circle
			(at 8.75 -3.03 180)
			(size 0.5 0.5)
			(layers "F.Cu" "F.Mask" "F.Paste")
			(net 234 "unconnected-(U9G-RSVDJ39_NC-PadJ39)")
			(pinfunction "RSVDJ39_NC")
			(pintype "passive+no_connect")
		)
		(pad "J41" smd circle
			(at 9.75 -3.03 180)
			(size 0.5 0.5)
			(layers "F.Cu" "F.Mask" "F.Paste")
			(net 177 "unconnected-(U9F-XTAL_PTP_XTAL_P-PadJ41)")
			(pinfunction "XTAL_PTP_XTAL_P")
			(pintype "passive+no_connect")
		)
		(pad "K2" smd circle
			(at -9.75 -2.165 180)
			(size 0.5 0.5)
			(layers "F.Cu" "F.Mask" "F.Paste")
			(net 95 "/X710-AT2 10GbE/MDIO3_SDA3")
			(pinfunction "MDIO3_SDA3")
			(pintype "passive")
		)
		(pad "K4" smd circle
			(at -8.75 -2.165 180)
			(size 0.5 0.5)
			(layers "F.Cu" "F.Mask" "F.Paste")
			(net 94 "/X710-AT2 10GbE/MDC3_SCL3")
			(pinfunction "MDC3_SCL3")
			(pintype "passive")
		)
		(pad "K6" smd circle
			(at -7.75 -2.165 180)
			(size 0.5 0.5)
			(layers "F.Cu" "F.Mask" "F.Paste")
			(net 286 "/X710-AT2 10GbE/~{P1_INT_R}")
			(pinfunction "SDP0_2")
			(pintype "tri_state")
		)
		(pad "K8" smd circle
			(at -6.75 -2.165 180)
			(size 0.5 0.5)
			(layers "F.Cu" "F.Mask" "F.Paste")
			(net 28 "GND")
			(pinfunction "VSSA")
			(pintype "passive")
		)
		(pad "K10" smd circle
			(at -5.75 -2.165 180)
			(size 0.5 0.5)
			(layers "F.Cu" "F.Mask" "F.Paste")
			(net 28 "GND")
			(pinfunction "VSSA")
			(pintype "passive")
		)
		(pad "K12" smd circle
			(at -4.75 -2.165 180)
			(size 0.5 0.5)
			(layers "F.Cu" "F.Mask" "F.Paste")
			(net 28 "GND")
			(pinfunction "VSSA")
			(pintype "passive")
		)
		(pad "K14" smd circle
			(at -3.75 -2.165 180)
			(size 0.5 0.5)
			(layers "F.Cu" "F.Mask" "F.Paste")
			(net 28 "GND")
			(pinfunction "VSSA")
			(pintype "passive")
		)
		(pad "K16" smd circle
			(at -2.75 -2.165 180)
			(size 0.5 0.5)
			(layers "F.Cu" "F.Mask" "F.Paste")
			(net 28 "GND")
			(pinfunction "VSSA")
			(pintype "passive")
		)
		(pad "K18" smd circle
			(at -1.75 -2.165 180)
			(size 0.5 0.5)
			(layers "F.Cu" "F.Mask" "F.Paste")
			(net 28 "GND")
			(pinfunction "VSS")
			(pintype "passive")
		)
		(pad "K20" smd circle
			(at -0.75 -2.165 180)
			(size 0.5 0.5)
			(layers "F.Cu" "F.Mask" "F.Paste")
			(net 28 "GND")
			(pinfunction "VSS")
			(pintype "passive")
		)
		(pad "K22" smd circle
			(at 0.25 -2.165 180)
			(size 0.5 0.5)
			(layers "F.Cu" "F.Mask" "F.Paste")
			(net 313 "unconnected-(U9E-RSVDK22_NC-PadK22)")
			(pinfunction "RSVDK22_NC")
			(pintype "passive+no_connect")
		)
		(pad "K24" smd circle
			(at 1.25 -2.165 180)
			(size 0.5 0.5)
			(layers "F.Cu" "F.Mask" "F.Paste")
			(net 188 "unconnected-(U9E-RSVDK24_NC-PadK24)")
			(pinfunction "RSVDK24_NC")
			(pintype "passive+no_connect")
		)
		(pad "K26" smd circle
			(at 2.25 -2.165 180)
			(size 0.5 0.5)
			(layers "F.Cu" "F.Mask" "F.Paste")
			(net 305 "unconnected-(U9G-RSVDK26_NC-PadK26)")
			(pinfunction "RSVDK26_NC")
			(pintype "passive+no_connect")
		)
		(pad "K28" smd circle
			(at 3.25 -2.165 180)
			(size 0.5 0.5)
			(layers "F.Cu" "F.Mask" "F.Paste")
			(net 246 "unconnected-(U9G-RSVDK28_NC-PadK28)")
			(pinfunction "RSVDK28_NC")
			(pintype "passive+no_connect")
		)
		(pad "K30" smd circle
			(at 4.25 -2.165 180)
			(size 0.5 0.5)
			(layers "F.Cu" "F.Mask" "F.Paste")
			(net 230 "unconnected-(U9F-RSVDK30_NC-PadK30)")
			(pinfunction "RSVDK30_NC")
			(pintype "passive+no_connect")
		)
		(pad "K32" smd circle
			(at 5.25 -2.165 180)
			(size 0.5 0.5)
			(layers "F.Cu" "F.Mask" "F.Paste")
			(net 343 "unconnected-(U9F-RSVDK32_NC-PadK32)")
			(pinfunction "RSVDK32_NC")
			(pintype "passive+no_connect")
		)
		(pad "K34" smd circle
			(at 6.25 -2.165 180)
			(size 0.5 0.5)
			(layers "F.Cu" "F.Mask" "F.Paste")
			(net 200 "unconnected-(U9G-RSVDK34_NC-PadK34)")
			(pinfunction "RSVDK34_NC")
			(pintype "passive+no_connect")
		)
		(pad "K36" smd circle
			(at 7.25 -2.165 180)
			(size 0.5 0.5)
			(layers "F.Cu" "F.Mask" "F.Paste")
			(net 352 "unconnected-(U9G-RSVDK36_NC-PadK36)")
			(pinfunction "RSVDK36_NC")
			(pintype "passive+no_connect")
		)
		(pad "K38" smd circle
			(at 8.25 -2.165 180)
			(size 0.5 0.5)
			(layers "F.Cu" "F.Mask" "F.Paste")
			(net 28 "GND")
			(pinfunction "VSSA")
			(pintype "passive")
		)
		(pad "K40" smd circle
			(at 9.25 -2.165 180)
			(size 0.5 0.5)
			(layers "F.Cu" "F.Mask" "F.Paste")
			(net 113 "/X710-AT2 Misc/RSVDK40_1P88V")
			(pinfunction "RSVDK40_1P88V")
			(pintype "passive")
		)
		(pad "K42" smd circle
			(at 10.25 -2.165 180)
			(size 0.5 0.5)
			(layers "F.Cu" "F.Mask" "F.Paste")
			(net 28 "GND")
			(pinfunction "RSVDK42_VSS")
			(pintype "passive")
		)
		(pad "L1" smd circle
			(at -10.25 -1.3 180)
			(size 0.5 0.5)
			(layers "F.Cu" "F.Mask" "F.Paste")
			(net 101 "/X710-AT2 10GbE/MDIO2_SDA2")
			(pinfunction "MDIO2_SDA2")
			(pintype "passive")
		)
		(pad "L3" smd circle
			(at -9.25 -1.3 180)
			(size 0.5 0.5)
			(layers "F.Cu" "F.Mask" "F.Paste")
			(net 96 "/X710-AT2 10GbE/MDC2_SCL2")
			(pinfunction "MDC2_SCL2")
			(pintype "passive")
		)
		(pad "L5" smd circle
			(at -8.25 -1.3 180)
			(size 0.5 0.5)
			(layers "F.Cu" "F.Mask" "F.Paste")
			(net 213 "unconnected-(U9C-SDP0_3-PadL5)")
			(pinfunction "SDP0_3")
			(pintype "passive+no_connect")
		)
		(pad "L7" smd circle
			(at -7.25 -1.3 180)
			(size 0.5 0.5)
			(layers "F.Cu" "F.Mask" "F.Paste")
			(net 108 "/X710-AT2 Misc/GPIO5_POR_BYPASS")
			(pinfunction "GPIO_5")
			(pintype "tri_state")
		)
		(pad "L9" smd circle
			(at -6.25 -1.3 180)
			(size 0.5 0.5)
			(layers "F.Cu" "F.Mask" "F.Paste")
			(net 7 "+3V3")
			(pinfunction "VCC3P3_TX")
			(pintype "power_in")
		)
		(pad "L11" smd circle
			(at -5.25 -1.3 180)
			(size 0.5 0.5)
			(layers "F.Cu" "F.Mask" "F.Paste")
			(net 1 "VCCA")
			(pinfunction "VCCA")
			(pintype "power_in")
		)
		(pad "L13" smd circle
			(at -4.25 -1.3 180)
			(size 0.5 0.5)
			(layers "F.Cu" "F.Mask" "F.Paste")
			(net 1 "VCCA")
			(pinfunction "VCCA")
			(pintype "passive")
		)
		(pad "L15" smd circle
			(at -3.25 -1.3 180)
			(size 0.5 0.5)
			(layers "F.Cu" "F.Mask" "F.Paste")
			(net 1 "VCCA")
			(pinfunction "VCCA")
			(pintype "passive")
		)
		(pad "L17" smd circle
			(at -2.25 -1.3 180)
			(size 0.5 0.5)
			(layers "F.Cu" "F.Mask" "F.Paste")
			(net 1 "VCCA")
			(pinfunction "VCCA")
			(pintype "passive")
		)
		(pad "L19" smd circle
			(at -1.25 -1.3 180)
			(size 0.5 0.5)
			(layers "F.Cu" "F.Mask" "F.Paste")
			(net 9 "VCCD")
			(pinfunction "VCCD")
			(pintype "power_in")
		)
		(pad "L21" smd circle
			(at -0.25 -1.3 180)
			(size 0.5 0.5)
			(layers "F.Cu" "F.Mask" "F.Paste")
			(net 9 "VCCD")
			(pinfunction "VCCD")
			(pintype "passive")
		)
		(pad "L23" smd circle
			(at 0.75 -1.3 180)
			(size 0.5 0.5)
			(layers "F.Cu" "F.Mask" "F.Paste")
			(net 205 "unconnected-(U9E-RSVDL23_NC-PadL23)")
			(pinfunction "RSVDL23_NC")
			(pintype "passive+no_connect")
		)
		(pad "L25" smd circle
			(at 1.75 -1.3 180)
			(size 0.5 0.5)
			(layers "F.Cu" "F.Mask" "F.Paste")
			(net 221 "unconnected-(U9E-RSVDL25_NC-PadL25)")
			(pinfunction "RSVDL25_NC")
			(pintype "passive+no_connect")
		)
		(pad "L27" smd circle
			(at 2.75 -1.3 180)
			(size 0.5 0.5)
			(layers "F.Cu" "F.Mask" "F.Paste")
			(net 281 "unconnected-(U9E-RSVDL27_NC-PadL27)")
			(pinfunction "RSVDL27_NC")
			(pintype "passive+no_connect")
		)
		(pad "L29" smd circle
			(at 3.75 -1.3 180)
			(size 0.5 0.5)
			(layers "F.Cu" "F.Mask" "F.Paste")
			(net 169 "unconnected-(U9G-RSVDL29_NC-PadL29)")
			(pinfunction "RSVDL29_NC")
			(pintype "passive+no_connect")
		)
		(pad "L31" smd circle
			(at 4.75 -1.3 180)
			(size 0.5 0.5)
			(layers "F.Cu" "F.Mask" "F.Paste")
			(net 28 "GND")
			(pinfunction "RSVDL31_VSS")
			(pintype "passive")
		)
		(pad "L33" smd circle
			(at 5.75 -1.3 180)
			(size 0.5 0.5)
			(layers "F.Cu" "F.Mask" "F.Paste")
			(net 112 "/X710-AT2 Misc/RSVDL33")
			(pinfunction "RSVDL33")
			(pintype "passive")
		)
		(pad "L35" smd circle
			(at 6.75 -1.3 180)
			(size 0.5 0.5)
			(layers "F.Cu" "F.Mask" "F.Paste")
			(net 168 "unconnected-(U9F-RSVDL35_NC-PadL35)")
			(pinfunction "RSVDL35_NC")
			(pintype "passive+no_connect")
		)
		(pad "L37" smd circle
			(at 7.75 -1.3 180)
			(size 0.5 0.5)
			(layers "F.Cu" "F.Mask" "F.Paste")
			(net 28 "GND")
			(pinfunction "RSVDL37_VSS")
			(pintype "passive")
		)
		(pad "L39" smd circle
			(at 8.75 -1.3 180)
			(size 0.5 0.5)
			(layers "F.Cu" "F.Mask" "F.Paste")
			(net 18 "+1V88")
			(pinfunction "VDDIO2")
			(pintype "power_in")
		)
		(pad "L41" smd circle
			(at 9.75 -1.3 180)
			(size 0.5 0.5)
			(layers "F.Cu" "F.Mask" "F.Paste")
			(net 382 "/X710-AT2 Misc/MDIO.MDC")
			(pinfunction "MDC")
			(pintype "input")
		)
		(pad "M2" smd circle
			(at -9.75 -0.435 180)
			(size 0.5 0.5)
			(layers "F.Cu" "F.Mask" "F.Paste")
			(net 103 "/X710-AT2 10GbE/MDIO1_SDA1")
			(pinfunction "MDIO1_SDA1")
			(pintype "passive")
		)
		(pad "M4" smd circle
			(at -8.75 -0.435 180)
			(size 0.5 0.5)
			(layers "F.Cu" "F.Mask" "F.Paste")
			(net 102 "/X710-AT2 10GbE/MDC1_SCL1")
			(pinfunction "MDC1_SCL1")
			(pintype "passive")
		)
		(pad "M6" smd circle
			(at -7.75 -0.435 180)
			(size 0.5 0.5)
			(layers "F.Cu" "F.Mask" "F.Paste")
			(net 176 "unconnected-(U9C-SDP3_2-PadM6)")
			(pinfunction "SDP3_2")
			(pintype "passive+no_connect")
		)
		(pad "M8" smd circle
			(at -6.75 -0.435 180)
			(size 0.5 0.5)
			(layers "F.Cu" "F.Mask" "F.Paste")
			(net 199 "unconnected-(U9C-SDP3_3-PadM8)")
			(pinfunction "SDP3_3")
			(pintype "passive+no_connect")
		)
		(pad "M10" smd circle
			(at -5.75 -0.435 180)
			(size 0.5 0.5)
			(layers "F.Cu" "F.Mask" "F.Paste")
			(net 28 "GND")
			(pinfunction "VSSA")
			(pintype "passive")
		)
		(pad "M12" smd circle
			(at -4.75 -0.435 180)
			(size 0.5 0.5)
			(layers "F.Cu" "F.Mask" "F.Paste")
			(net 28 "GND")
			(pinfunction "VSSA")
			(pintype "passive")
		)
		(pad "M14" smd circle
			(at -3.75 -0.435 180)
			(size 0.5 0.5)
			(layers "F.Cu" "F.Mask" "F.Paste")
			(net 28 "GND")
			(pinfunction "VSSA")
			(pintype "passive")
		)
		(pad "M16" smd circle
			(at -2.75 -0.435 180)
			(size 0.5 0.5)
			(layers "F.Cu" "F.Mask" "F.Paste")
			(net 28 "GND")
			(pinfunction "VSSA")
			(pintype "passive")
		)
		(pad "M18" smd circle
			(at -1.75 -0.435 180)
			(size 0.5 0.5)
			(layers "F.Cu" "F.Mask" "F.Paste")
			(net 28 "GND")
			(pinfunction "VSS")
			(pintype "passive")
		)
	)
)
